# S9S_MB_2U (Grand Teton) — schematic netlist excerpt (pin names and nets, part order shuffled) for the footprints in the layout excerpt that follows; sources: Cadence DE-HDL packaged netlist, KiCad conversion of 03242023_DA0F0TMBIJ0_F0T_Motherboard_J_brd_V01_OCP.brd

C369  Q_CAP  47UF 4V 20% X6S  pkg C0805  page 76 : A = PVCCIN_CPU0 ; B = GND
C1889  Q_CAP  0.1UF 25V 10% X7R  pkg 0402  page 212 : A = VFG3P3_CLK_GEN ; B = GND
PC1183_P0_3  Q_CAP  1UF 16V 10% X6S  pkg C0402  page 272 : A = PVCCFA_EHV_FIVRA_CPU0 ; B = GND

(kicad_pcb
	(version 20260206)
	(generator "pcbnew")
	(generator_version "10.0")
	(general
		(thickness 1.6)
		(legacy_teardrops no)
	)
	(paper "A4")
	(title_block
		(title "03242023_DA0F0TMBIJ0_F0T_Motherboard_J_brd_V01_OCP.brd")
		(comment 1 "Grand Teton / footprints 5705-5707 of 6105")
	)
	(layers
		(0 "F.Cu" signal "TOP")
		(4 "In1.Cu" signal "GND")
		(6 "In2.Cu" signal "IN1")
		(8 "In3.Cu" signal "GND1")
		(10 "In4.Cu" signal "IN2")
		(12 "In5.Cu" signal "GND2")
		(14 "In6.Cu" signal "IN3")
		(16 "In7.Cu" signal "GND3")
		(18 "In8.Cu" signal "VCC")
		(20 "In9.Cu" signal "VCC1")
		(22 "In10.Cu" signal "GND4")
		(24 "In11.Cu" signal "IN4")
		(26 "In12.Cu" signal "GND5")
		(28 "In13.Cu" signal "IN5")
		(30 "In14.Cu" signal "GND6")
		(32 "In15.Cu" signal "IN6")
		(34 "In16.Cu" signal "GND7")
		(2 "B.Cu" signal "BOTTOM")
		(9 "F.Adhes" user "F.Adhesive")
		(11 "B.Adhes" user "B.Adhesive")
		(13 "F.Paste" user "Package Geometry/Pastemask Top")
		(15 "B.Paste" user "Package Geometry/Pastemask Bottom")
		(5 "F.SilkS" user "Ref Des/Silkscreen Top")
		(7 "B.SilkS" user "Ref Des/Silkscreen Bottom")
		(1 "F.Mask" user "Board Geometry/Soldermask Top")
		(3 "B.Mask" user "Board Geometry/Soldermask Bottom")
		(17 "Dwgs.User" user "User.Drawings")
		(19 "Cmts.User" user "User.Comments")
		(21 "Eco1.User" user "User.Eco1")
		(23 "Eco2.User" user "User.Eco2")
		(25 "Edge.Cuts" user "Board Geometry/Outline")
		(27 "Margin" user)
		(31 "F.CrtYd" user "Package Geometry/Place Bound Top")
		(29 "B.CrtYd" user "Package Geometry/Place Bound Bottom")
		(35 "F.Fab" user "Ref Des/Assembly Top")
		(33 "B.Fab" user "Ref Des/Assembly Bottom")
	)
	(footprint ""
		(layer "B.Cu")
		(at 429.14951 -353.05111 -90)
		(property "Reference" "PC1183_P0_3"
			(at 0 0 90)
			(layer "B.SilkS")
			(hide yes)
			(effects
				(font
					(size 1.27 1.27)
				)
				(justify mirror)
			)
		)
		(property "Value" ""
			(at 0 0 90)
			(layer "B.Fab")
			(effects
				(font
					(size 1.27 1.27)
				)
				(justify mirror)
			)
		)
		(duplicate_pad_numbers_are_jumpers no)
		(fp_line
			(start -0.7874 0.4064)
			(end 0.7874 0.4064)
			(stroke
				(width 0.1524)
				(type default)
			)
			(layer "B.SilkS")
		)
		(fp_line
			(start 0.7874 0.4064)
			(end 0.7874 -0.4064)
			(stroke
				(width 0.1524)
				(type default)
			)
			(layer "B.SilkS")
		)
		(fp_line
			(start -0.7874 -0.4064)
			(end -0.7874 0.4064)
			(stroke
				(width 0.1524)
				(type default)
			)
			(layer "B.SilkS")
		)
		(fp_line
			(start 0.7874 -0.4064)
			(end -0.7874 -0.4064)
			(stroke
				(width 0.1524)
				(type default)
			)
			(layer "B.SilkS")
		)
		(fp_line
			(start -0.67945 0.3048)
			(end -0.120396 0.3048)
			(stroke
				(width 0.1)
				(type default)
			)
			(layer "B.Fab")
		)
		(fp_line
			(start -0.120396 0.3048)
			(end -0.120396 0.2794)
			(stroke
				(width 0.1)
				(type default)
			)
			(layer "B.Fab")
		)
		(fp_line
			(start 0.12065 0.3048)
			(end 0.67945 0.3048)
			(stroke
				(width 0.1)
				(type default)
			)
			(layer "B.Fab")
		)
		(fp_line
			(start 0.67945 0.3048)
			(end 0.67945 -0.305054)
			(stroke
				(width 0.1)
				(type default)
			)
			(layer "B.Fab")
		)
		(fp_line
			(start -0.120396 0.2794)
			(end 0.12065 0.2794)
			(stroke
				(width 0.1)
				(type default)
			)
			(layer "B.Fab")
		)
		(fp_line
			(start 0.12065 0.2794)
			(end 0.12065 0.3048)
			(stroke
				(width 0.1)
				(type default)
			)
			(layer "B.Fab")
		)
		(fp_line
			(start -0.12065 -0.2794)
			(end -0.12065 -0.3048)
			(stroke
				(width 0.1)
				(type default)
			)
			(layer "B.Fab")
		)
		(fp_line
			(start 0.12065 -0.2794)
			(end -0.12065 -0.2794)
			(stroke
				(width 0.1)
				(type default)
			)
			(layer "B.Fab")
		)
		(fp_line
			(start -0.67945 -0.3048)
			(end -0.67945 0.3048)
			(stroke
				(width 0.1)
				(type default)
			)
			(layer "B.Fab")
		)
		(fp_line
			(start -0.12065 -0.3048)
			(end -0.67945 -0.3048)
			(stroke
				(width 0.1)
				(type default)
			)
			(layer "B.Fab")
		)
		(fp_line
			(start 0.12065 -0.305054)
			(end 0.12065 -0.2794)
			(stroke
				(width 0.1)
				(type default)
			)
			(layer "B.Fab")
		)
		(fp_line
			(start 0.67945 -0.305054)
			(end 0.12065 -0.305054)
			(stroke
				(width 0.1)
				(type default)
			)
			(layer "B.Fab")
		)
		(pad "1" smd circle
			(at 0.40005 0 90)
			(size 0 0)
			(layers "B.Cu" "B.Mask" "B.Paste")
			(net "PVCCFA_EHV_FIVRA_CPU0")
		)
		(pad "2" smd circle
			(at -0.40005 0 90)
			(size 0 0)
			(layers "B.Cu" "B.Mask" "B.Paste")
			(net "GND")
		)
	)
	(footprint ""
		(layer "B.Cu")
		(at 353.610418 -294.009826)
		(property "Reference" "C369"
			(at 0 0 0)
			(layer "B.SilkS")
			(hide yes)
			(effects
				(font
					(size 1.27 1.27)
				)
				(justify mirror)
			)
		)
		(property "Value" ""
			(at 0 0 0)
			(layer "B.Fab")
			(effects
				(font
					(size 1.27 1.27)
				)
				(justify mirror)
			)
		)
		(duplicate_pad_numbers_are_jumpers no)
		(fp_line
			(start -1.524 -0.762)
			(end -1.524 0.762)
			(stroke
				(width 0.1524)
				(type default)
			)
			(layer "B.SilkS")
		)
		(fp_line
			(start -1.524 0.762)
			(end 1.524 0.762)
			(stroke
				(width 0.1524)
				(type default)
			)
			(layer "B.SilkS")
		)
		(fp_line
			(start 1.524 -0.762)
			(end -1.524 -0.762)
			(stroke
				(width 0.1524)
				(type default)
			)
			(layer "B.SilkS")
		)
		(fp_line
			(start 1.524 0.762)
			(end 1.524 -0.762)
			(stroke
				(width 0.1524)
				(type default)
			)
			(layer "B.SilkS")
		)
		(fp_line
			(start -1.1049 -0.724916)
			(end 1.1049 -0.724916)
			(stroke
				(width 0.1)
				(type default)
			)
			(layer "B.Fab")
		)
		(fp_line
			(start -1.1049 0.724916)
			(end -1.1049 -0.724916)
			(stroke
				(width 0.1)
				(type default)
			)
			(layer "B.Fab")
		)
		(fp_line
			(start 1.1049 -0.724916)
			(end 1.1049 0.724916)
			(stroke
				(width 0.1)
				(type default)
			)
			(layer "B.Fab")
		)
		(fp_line
			(start 1.1049 0.724916)
			(end -1.1049 0.724916)
			(stroke
				(width 0.1)
				(type default)
			)
			(layer "B.Fab")
		)
		(pad "1" smd rect
			(at 0.889 0)
			(size 1.016 1.27)
			(layers "B.Cu" "B.Mask" "B.Paste")
			(net "PVCCIN_CPU0")
		)
		(pad "2" smd rect
			(at -0.889 0)
			(size 1.016 1.27)
			(layers "B.Cu" "B.Mask" "B.Paste")
			(net "GND")
		)
	)
	(footprint ""
		(layer "B.Cu")
		(at 236.925612 -250.480322)
		(property "Reference" "C1889"
			(at 0 0 0)
			(layer "B.SilkS")
			(hide yes)
			(effects
				(font
					(size 1.27 1.27)
				)
				(justify mirror)
			)
		)
		(property "Value" ""
			(at 0 0 0)
			(layer "B.Fab")
			(effects
				(font
					(size 1.27 1.27)
				)
				(justify mirror)
			)
		)
		(duplicate_pad_numbers_are_jumpers no)
		(fp_line
			(start -0.7874 -0.4064)
			(end -0.7874 0.4064)
			(stroke
				(width 0.1524)
				(type default)
			)
			(layer "B.SilkS")
		)
		(fp_line
			(start -0.7874 0.4064)
			(end 0.7874 0.4064)
			(stroke
				(width 0.1524)
				(type default)
			)
			(layer "B.SilkS")
		)
		(fp_line
			(start 0.7874 -0.4064)
			(end -0.7874 -0.4064)
			(stroke
				(width 0.1524)
				(type default)
			)
			(layer "B.SilkS")
		)
		(fp_line
			(start 0.7874 0.4064)
			(end 0.7874 -0.4064)
			(stroke
				(width 0.1524)
				(type default)
			)
			(layer "B.SilkS")
		)
		(fp_line
			(start -0.67945 -0.3048)
			(end -0.67945 0.3048)
			(stroke
				(width 0.1)
				(type default)
			)
			(layer "B.Fab")
		)
		(fp_line
			(start -0.67945 0.3048)
			(end -0.120396 0.3048)
			(stroke
				(width 0.1)
				(type default)
			)
			(layer "B.Fab")
		)
		(fp_line
			(start -0.12065 -0.3048)
			(end -0.67945 -0.3048)
			(stroke
				(width 0.1)
				(type default)
			)
			(layer "B.Fab")
		)
		(fp_line
			(start -0.12065 -0.2794)
			(end -0.12065 -0.3048)
			(stroke
				(width 0.1)
				(type default)
			)
			(layer "B.Fab")
		)
		(fp_line
			(start -0.120396 0.2794)
			(end 0.12065 0.2794)
			(stroke
				(width 0.1)
				(type default)
			)
			(layer "B.Fab")
		)
		(fp_line
			(start -0.120396 0.3048)
			(end -0.120396 0.2794)
			(stroke
				(width 0.1)
				(type default)
			)
			(layer "B.Fab")
		)
		(fp_line
			(start 0.12065 -0.305054)
			(end 0.12065 -0.2794)
			(stroke
				(width 0.1)
				(type default)
			)
			(layer "B.Fab")
		)
		(fp_line
			(start 0.12065 -0.2794)
			(end -0.12065 -0.2794)
			(stroke
				(width 0.1)
				(type default)
			)
			(layer "B.Fab")
		)
		(fp_line
			(start 0.12065 0.2794)
			(end 0.12065 0.3048)
			(stroke
				(width 0.1)
				(type default)
			)
			(layer "B.Fab")
		)
		(fp_line
			(start 0.12065 0.3048)
			(end 0.67945 0.3048)
			(stroke
				(width 0.1)
				(type default)
			)
			(layer "B.Fab")
		)
		(fp_line
			(start 0.67945 -0.305054)
			(end 0.12065 -0.305054)
			(stroke
				(width 0.1)
				(type default)
			)
			(layer "B.Fab")
		)
		(fp_line
			(start 0.67945 0.3048)
			(end 0.67945 -0.305054)
			(stroke
				(width 0.1)
				(type default)
			)
			(layer "B.Fab")
		)
		(pad "1" smd circle
			(at 0.40005 0 180)
			(size 0 0)
			(layers "B.Cu" "B.Mask" "B.Paste")
			(net "VFG3P3_CLK_GEN")
		)
		(pad "2" smd circle
			(at -0.40005 0 180)
			(size 0 0)
			(layers "B.Cu" "B.Mask" "B.Paste")
			(net "GND")
		)
	)
)
